(kicad_pcb
	(version 20260206)
	(generator "pcbnew")
	(generator_version "10.0")
	(general
		(thickness 1.6)
		(legacy_teardrops no)
	)
	(paper "A4")
	(title_block
		(title "Bryce Canyon_SCC_16316-1_OCP.brd")
		(comment 1 "Bryce Canyon / footprints 649-657 of 1561")
	)
	(layers
		(0 "F.Cu" signal "TOP")
		(4 "In1.Cu" signal "L2GND")
		(6 "In2.Cu" signal "L3")
		(8 "In3.Cu" signal "L4VCC")
		(10 "In4.Cu" signal "L5VCC")
		(12 "In5.Cu" signal "L6")
		(14 "In6.Cu" signal "L7GND")
		(2 "B.Cu" signal "BOTTOM")
		(9 "F.Adhes" user "F.Adhesive")
		(11 "B.Adhes" user "B.Adhesive")
		(13 "F.Paste" user "Package Geometry/Pastemask Top")
		(15 "B.Paste" user "Package Geometry/Pastemask Bottom")
		(5 "F.SilkS" user "Ref Des/Silkscreen Top")
		(7 "B.SilkS" user "Ref Des/Silkscreen Bottom")
		(1 "F.Mask" user "Board Geometry/Soldermask Top")
		(3 "B.Mask" user "Board Geometry/Soldermask Bottom")
		(17 "Dwgs.User" user "User.Drawings")
		(19 "Cmts.User" user "User.Comments")
		(21 "Eco1.User" user "User.Eco1")
		(23 "Eco2.User" user "User.Eco2")
		(25 "Edge.Cuts" user "Board Geometry/Outline")
		(27 "Margin" user)
		(31 "F.CrtYd" user "Package Geometry/Place Bound Top")
		(29 "B.CrtYd" user "Package Geometry/Place Bound Bottom")
		(35 "F.Fab" user "Ref Des/Assembly Top")
		(33 "B.Fab" user "Ref Des/Assembly Bottom")
	)
	(footprint ""
		(layer "F.Cu")
		(at 198.53656 -74.46772 90)
		(property "Reference" "R298"
			(at 0 0 90)
			(layer "F.SilkS")
			(hide yes)
			(effects
				(font
					(size 1.27 1.27)
				)
			)
		)
		(property "Value" "0R2J-2-GP"
			(at 0.064008 -3.993896 90)
			(unlocked yes)
			(layer "F.Fab")
			(hide yes)
			(effects
				(font
					(size 1.016 1.016)
					(thickness 0.1524)
				)
			)
		)
		(property "Device Type" "R402H16"
			(at 0.064008 -5.517896 90)
			(unlocked yes)
			(layer "F.Fab")
			(hide yes)
			(effects
				(font
					(size 1.016 1.016)
					(thickness 0.1524)
				)
			)
		)
		(duplicate_pad_numbers_are_jumpers no)
		(fp_line
			(start 0.508 -0.9398)
			(end -0.508 -0.9398)
			(stroke
				(width 0.1524)
				(type default)
			)
			(layer "F.SilkS")
		)
		(fp_line
			(start -0.508 -0.9398)
			(end -0.508 0.9398)
			(stroke
				(width 0.1524)
				(type default)
			)
			(layer "F.SilkS")
		)
		(fp_rect
			(start -0.508 0.9398)
			(end 0.508 -0.9398)
			(stroke
				(width 0)
				(type default)
			)
			(fill no)
			(layer "F.CrtYd")
		)
		(fp_rect
			(start -0.508 0.9398)
			(end 0.508 -0.9398)
			(stroke
				(width 0)
				(type default)
			)
			(fill no)
			(layer "F.Fab")
		)
		(pad "1" smd custom
			(at 0 -0.4445 90)
			(size 0.1397 0.1397)
			(layers "F.Cu" "F.Mask" "F.Paste")
			(net "IOC_UART_0_RX_R")
			(options
				(clearance outline)
				(anchor circle)
			)
			(primitives
				(gr_poly
					(pts
						(arc
							(start -0.1778 -0.2794)
							(mid -0.249642 -0.249642)
							(end -0.2794 -0.1778)
						)
						(arc
							(start -0.2794 0.1778)
							(mid -0.249642 0.249642)
							(end -0.1778 0.2794)
						)
						(arc
							(start 0.1778 0.2794)
							(mid 0.249642 0.249642)
							(end 0.2794 0.1778)
						)
						(arc
							(start 0.2794 -0.1778)
							(mid 0.249642 -0.249642)
							(end 0.1778 -0.2794)
						)
					)
					(width 0)
					(fill yes)
				)
			)
		)
		(pad "2" smd custom
			(at 0 0.4445 90)
			(size 0.1397 0.1397)
			(layers "F.Cu" "F.Mask" "F.Paste")
			(net "IOC_UART_0_RX")
			(options
				(clearance outline)
				(anchor circle)
			)
			(primitives
				(gr_poly
					(pts
						(arc
							(start -0.1778 -0.2794)
							(mid -0.249642 -0.249642)
							(end -0.2794 -0.1778)
						)
						(arc
							(start -0.2794 0.1778)
							(mid -0.249642 0.249642)
							(end -0.1778 0.2794)
						)
						(arc
							(start 0.1778 0.2794)
							(mid 0.249642 0.249642)
							(end 0.2794 0.1778)
						)
						(arc
							(start 0.2794 -0.1778)
							(mid 0.249642 -0.249642)
							(end 0.1778 -0.2794)
						)
					)
					(width 0)
					(fill yes)
				)
			)
		)
	)
	(footprint ""
		(layer "F.Cu")
		(at 136.398 -109.601 -90)
		(property "Reference" "C694"
			(at 0 0 270)
			(layer "F.SilkS")
			(hide yes)
			(effects
				(font
					(size 1.27 1.27)
				)
			)
		)
		(property "Value" "SC10U6D3V5KX-4GP"
			(at -0.0762 -6.1214 270)
			(unlocked yes)
			(layer "F.Fab")
			(hide yes)
			(effects
				(font
					(size 1.016 1.016)
					(thickness 0.1524)
				)
			)
		)
		(property "Device Type" "C805H58"
			(at -0.0762 -8.1534 270)
			(unlocked yes)
			(layer "F.Fab")
			(hide yes)
			(effects
				(font
					(size 1.016 1.016)
					(thickness 0.1524)
				)
			)
		)
		(duplicate_pad_numbers_are_jumpers no)
		(fp_line
			(start 0.635 0)
			(end -0.635 0)
			(stroke
				(width 0.508)
				(type default)
			)
			(layer "F.SilkS")
		)
		(fp_rect
			(start -0.9652 1.778)
			(end 0.9652 -1.778)
			(stroke
				(width 0)
				(type default)
			)
			(fill no)
			(layer "F.CrtYd")
		)
		(fp_poly
			(pts
				(xy -0.9652 -1.778) (xy 0.9652 -1.778) (xy 0.9652 1.778) (xy -0.9652 1.778)
			)
			(stroke
				(width 0)
				(type default)
			)
			(fill no)
			(layer "F.Fab")
		)
		(pad "1" smd rect
			(at 0 -0.9652 270)
			(size 1.397 1.143)
			(layers "F.Cu" "F.Mask" "F.Paste")
			(net "P1V5_E_OUT")
		)
		(pad "2" smd rect
			(at 0 0.9652 270)
			(size 1.397 1.143)
			(layers "F.Cu" "F.Mask" "F.Paste")
			(net "GND")
		)
	)
	(footprint ""
		(layer "F.Cu")
		(at 65.4685 -108.331 90)
		(property "Reference" "R514"
			(at 0 0 90)
			(layer "F.SilkS")
			(hide yes)
			(effects
				(font
					(size 1.27 1.27)
				)
			)
		)
		(property "Value" "2K7R2F-GP"
			(at 0.064008 -3.993896 90)
			(unlocked yes)
			(layer "F.Fab")
			(hide yes)
			(effects
				(font
					(size 1.016 1.016)
					(thickness 0.1524)
				)
			)
		)
		(property "Device Type" "R402H16"
			(at 0.064008 -5.517896 90)
			(unlocked yes)
			(layer "F.Fab")
			(hide yes)
			(effects
				(font
					(size 1.016 1.016)
					(thickness 0.1524)
				)
			)
		)
		(duplicate_pad_numbers_are_jumpers no)
		(fp_line
			(start 0.508 -0.9398)
			(end -0.508 -0.9398)
			(stroke
				(width 0.1524)
				(type default)
			)
			(layer "F.SilkS")
		)
		(fp_line
			(start -0.508 -0.9398)
			(end -0.508 0.9398)
			(stroke
				(width 0.1524)
				(type default)
			)
			(layer "F.SilkS")
		)
		(fp_rect
			(start -0.508 0.9398)
			(end 0.508 -0.9398)
			(stroke
				(width 0)
				(type default)
			)
			(fill no)
			(layer "F.CrtYd")
		)
		(fp_rect
			(start -0.508 0.9398)
			(end 0.508 -0.9398)
			(stroke
				(width 0)
				(type default)
			)
			(fill no)
			(layer "F.Fab")
		)
		(pad "1" smd custom
			(at 0 -0.4445 90)
			(size 0.1397 0.1397)
			(layers "F.Cu" "F.Mask" "F.Paste")
			(net "P3V3_LL")
			(options
				(clearance outline)
				(anchor circle)
			)
			(primitives
				(gr_poly
					(pts
						(arc
							(start -0.1778 -0.2794)
							(mid -0.249642 -0.249642)
							(end -0.2794 -0.1778)
						)
						(arc
							(start -0.2794 0.1778)
							(mid -0.249642 0.249642)
							(end -0.1778 0.2794)
						)
						(arc
							(start 0.1778 0.2794)
							(mid 0.249642 0.249642)
							(end 0.2794 0.1778)
						)
						(arc
							(start 0.2794 -0.1778)
							(mid 0.249642 -0.249642)
							(end 0.1778 -0.2794)
						)
					)
					(width 0)
					(fill yes)
				)
			)
		)
		(pad "2" smd custom
			(at 0 0.4445 90)
			(size 0.1397 0.1397)
			(layers "F.Cu" "F.Mask" "F.Paste")
			(net "P3V3_LL_R")
			(options
				(clearance outline)
				(anchor circle)
			)
			(primitives
				(gr_poly
					(pts
						(arc
							(start -0.1778 -0.2794)
							(mid -0.249642 -0.249642)
							(end -0.2794 -0.1778)
						)
						(arc
							(start -0.2794 0.1778)
							(mid -0.249642 0.249642)
							(end -0.1778 0.2794)
						)
						(arc
							(start 0.1778 0.2794)
							(mid 0.249642 0.249642)
							(end 0.2794 0.1778)
						)
						(arc
							(start 0.2794 -0.1778)
							(mid 0.249642 -0.249642)
							(end 0.1778 -0.2794)
						)
					)
					(width 0)
					(fill yes)
				)
			)
		)
	)
	(footprint ""
		(layer "F.Cu")
		(at 39.8018 -49.7332 180)
		(property "Reference" "C671"
			(at 0 0 180)
			(layer "F.SilkS")
			(hide yes)
			(effects
				(font
					(size 1.27 1.27)
				)
			)
		)
		(property "Value" "SC10U16V5KX-7-GP-U"
			(at -0.0762 -6.1214 180)
			(unlocked yes)
			(layer "F.Fab")
			(hide yes)
			(effects
				(font
					(size 1.016 1.016)
					(thickness 0.1524)
				)
			)
		)
		(property "Device Type" "C805H58"
			(at -0.0762 -8.1534 180)
			(unlocked yes)
			(layer "F.Fab")
			(hide yes)
			(effects
				(font
					(size 1.016 1.016)
					(thickness 0.1524)
				)
			)
		)
		(duplicate_pad_numbers_are_jumpers no)
		(fp_line
			(start 0.635 0)
			(end -0.635 0)
			(stroke
				(width 0.508)
				(type default)
			)
			(layer "F.SilkS")
		)
		(fp_rect
			(start -0.9652 1.778)
			(end 0.9652 -1.778)
			(stroke
				(width 0)
				(type default)
			)
			(fill no)
			(layer "F.CrtYd")
		)
		(fp_poly
			(pts
				(xy -0.9652 -1.778) (xy 0.9652 -1.778) (xy 0.9652 1.778) (xy -0.9652 1.778)
			)
			(stroke
				(width 0)
				(type default)
			)
			(fill no)
			(layer "F.Fab")
		)
		(pad "1" smd rect
			(at 0 -0.9652 180)
			(size 1.397 1.143)
			(layers "F.Cu" "F.Mask" "F.Paste")
			(net "P12V_STBY_VIN_Q7")
		)
		(pad "2" smd rect
			(at 0 0.9652 180)
			(size 1.397 1.143)
			(layers "F.Cu" "F.Mask" "F.Paste")
			(net "GND")
		)
	)
	(footprint ""
		(layer "F.Cu")
		(at 137.595356 -84.709762)
		(property "Reference" "R58"
			(at 0 0 0)
			(layer "F.SilkS")
			(hide yes)
			(effects
				(font
					(size 1.27 1.27)
				)
			)
		)
		(property "Value" "4K7R2F-GP"
			(at 0.064008 -3.993896 0)
			(unlocked yes)
			(layer "F.Fab")
			(hide yes)
			(effects
				(font
					(size 1.016 1.016)
					(thickness 0.1524)
				)
			)
		)
		(property "Device Type" "R402H16"
			(at 0.064008 -5.517896 0)
			(unlocked yes)
			(layer "F.Fab")
			(hide yes)
			(effects
				(font
					(size 1.016 1.016)
					(thickness 0.1524)
				)
			)
		)
		(duplicate_pad_numbers_are_jumpers no)
		(fp_line
			(start -0.508 -0.9398)
			(end -0.508 0.9398)
			(stroke
				(width 0.1524)
				(type default)
			)
			(layer "F.SilkS")
		)
		(fp_line
			(start 0.508 -0.9398)
			(end -0.508 -0.9398)
			(stroke
				(width 0.1524)
				(type default)
			)
			(layer "F.SilkS")
		)
		(fp_rect
			(start -0.508 0.9398)
			(end 0.508 -0.9398)
			(stroke
				(width 0)
				(type default)
			)
			(fill no)
			(layer "F.CrtYd")
		)
		(fp_rect
			(start -0.508 0.9398)
			(end 0.508 -0.9398)
			(stroke
				(width 0)
				(type default)
			)
			(fill no)
			(layer "F.Fab")
		)
		(pad "1" smd custom
			(at 0 -0.4445)
			(size 0.1397 0.1397)
			(layers "F.Cu" "F.Mask" "F.Paste")
			(net "P1V8_E")
			(options
				(clearance outline)
				(anchor circle)
			)
			(primitives
				(gr_poly
					(pts
						(arc
							(start -0.1778 -0.2794)
							(mid -0.249642 -0.249642)
							(end -0.2794 -0.1778)
						)
						(arc
							(start -0.2794 0.1778)
							(mid -0.249642 0.249642)
							(end -0.1778 0.2794)
						)
						(arc
							(start 0.1778 0.2794)
							(mid 0.249642 0.249642)
							(end 0.2794 0.1778)
						)
						(arc
							(start 0.2794 -0.1778)
							(mid 0.249642 -0.249642)
							(end 0.1778 -0.2794)
						)
					)
					(width 0)
					(fill yes)
				)
			)
		)
		(pad "2" smd custom
			(at 0 0.4445)
			(size 0.1397 0.1397)
			(layers "F.Cu" "F.Mask" "F.Paste")
			(net "I2C_DRIVE_INS_SCL5_LS")
			(options
				(clearance outline)
				(anchor circle)
			)
			(primitives
				(gr_poly
					(pts
						(arc
							(start -0.1778 -0.2794)
							(mid -0.249642 -0.249642)
							(end -0.2794 -0.1778)
						)
						(arc
							(start -0.2794 0.1778)
							(mid -0.249642 0.249642)
							(end -0.1778 0.2794)
						)
						(arc
							(start 0.1778 0.2794)
							(mid 0.249642 0.249642)
							(end 0.2794 0.1778)
						)
						(arc
							(start 0.2794 -0.1778)
							(mid 0.249642 -0.249642)
							(end 0.1778 -0.2794)
						)
					)
					(width 0)
					(fill yes)
				)
			)
		)
	)
	(footprint ""
		(layer "F.Cu")
		(at 62.384686 -21.500846 180)
		(property "Reference" "U49"
			(at 0 0 180)
			(layer "F.SilkS")
			(hide yes)
			(effects
				(font
					(size 1.27 1.27)
				)
			)
		)
		(property "Value" "SNLVC1G126DCKR-GP"
			(at -2.3368 -8.6868 180)
			(unlocked yes)
			(layer "F.Fab")
			(hide yes)
			(effects
				(font
					(size 1.016 1.016)
					(thickness 0.1524)
				)
			)
		)
		(property "Device Type" "SC70-5H44"
			(at -2.3114 -10.414 180)
			(unlocked yes)
			(layer "F.Fab")
			(hide yes)
			(effects
				(font
					(size 1.016 1.016)
					(thickness 0.1524)
				)
			)
		)
		(duplicate_pad_numbers_are_jumpers no)
		(fp_line
			(start 1.3843 -1.8034)
			(end 1.3843 -1.1176)
			(stroke
				(width 0.3302)
				(type default)
			)
			(layer "F.SilkS")
		)
		(fp_line
			(start 1.27 1.7018)
			(end -1.27 1.7018)
			(stroke
				(width 0.1524)
				(type default)
			)
			(layer "F.SilkS")
		)
		(fp_line
			(start 1.27 -1.7018)
			(end 1.27 1.7018)
			(stroke
				(width 0.1524)
				(type default)
			)
			(layer "F.SilkS")
		)
		(fp_line
			(start 0.6604 -1.8034)
			(end 1.3843 -1.8034)
			(stroke
				(width 0.3302)
				(type default)
			)
			(layer "F.SilkS")
		)
		(fp_line
			(start -1.27 1.7018)
			(end -1.27 -1.7018)
			(stroke
				(width 0.1524)
				(type default)
			)
			(layer "F.SilkS")
		)
		(fp_line
			(start -1.27 -1.7018)
			(end 1.27 -1.7018)
			(stroke
				(width 0.1524)
				(type default)
			)
			(layer "F.SilkS")
		)
		(fp_rect
			(start -1.524 1.9558)
			(end 1.524 -1.9558)
			(stroke
				(width 0)
				(type default)
			)
			(fill no)
			(layer "F.CrtYd")
		)
		(fp_poly
			(pts
				(xy -1.524 -1.9558) (xy 1.524 -1.9558) (xy 1.524 1.9558) (xy -1.524 1.9558)
			)
			(stroke
				(width 0)
				(type default)
			)
			(fill no)
			(layer "F.Fab")
		)
		(pad "1" smd rect
			(at 0.65024 -0.8255 180)
			(size 0.4064 1.2192)
			(layers "F.Cu" "F.Mask" "F.Paste")
			(net "U49_OE")
		)
		(pad "2" smd rect
			(at 0 -0.8255 180)
			(size 0.4064 1.2192)
			(layers "F.Cu" "F.Mask" "F.Paste")
			(net "SCC_STBY_PGOOD_U49")
		)
		(pad "3" smd rect
			(at -0.65024 -0.8255 180)
			(size 0.4064 1.2192)
			(layers "F.Cu" "F.Mask" "F.Paste")
			(net "GND")
		)
		(pad "4" smd rect
			(at -0.65024 0.8255 180)
			(size 0.4064 1.2192)
			(layers "F.Cu" "F.Mask" "F.Paste")
			(net "SCC_FULL_PWR_EN_U49")
		)
		(pad "5" smd rect
			(at 0.65024 0.8255 180)
			(size 0.4064 1.2192)
			(layers "F.Cu" "F.Mask" "F.Paste")
			(net "P3V3")
		)
	)
	(footprint ""
		(layer "F.Cu")
		(at 151.257 -85.8266 -90)
		(property "Reference" "C575"
			(at 0 0 270)
			(layer "F.SilkS")
			(hide yes)
			(effects
				(font
					(size 1.27 1.27)
				)
			)
		)
		(property "Value" "SCD1U16V2KX-3GP"
			(at 1.1811 -2.7051 270)
			(unlocked yes)
			(layer "F.Fab")
			(hide yes)
			(effects
				(font
					(size 1.016 1.016)
					(thickness 0.1524)
				)
			)
		)
		(property "Device Type" "C402H22"
			(at 1.1811 -4.2291 270)
			(unlocked yes)
			(layer "F.Fab")
			(hide yes)
			(effects
				(font
					(size 1.016 1.016)
					(thickness 0.1524)
				)
			)
		)
		(duplicate_pad_numbers_are_jumpers no)
		(fp_rect
			(start -0.4318 0.9525)
			(end 0.4318 -0.9525)
			(stroke
				(width 0)
				(type default)
			)
			(fill no)
			(layer "F.CrtYd")
		)
		(fp_rect
			(start -0.4318 0.9525)
			(end 0.4318 -0.9525)
			(stroke
				(width 0)
				(type default)
			)
			(fill no)
			(layer "F.Fab")
		)
		(pad "1" smd custom
			(at 0 -0.4445 270)
			(size 0.1524 0.1524)
			(layers "F.Cu" "F.Mask" "F.Paste")
			(net "P3V3_SENSE")
			(options
				(clearance outline)
				(anchor circle)
			)
			(primitives
				(gr_poly
					(pts
						(arc
							(start 0.3048 -0.2032)
							(mid 0.275042 -0.275042)
							(end 0.2032 -0.3048)
						)
						(arc
							(start -0.2032 -0.3048)
							(mid -0.275042 -0.275042)
							(end -0.3048 -0.2032)
						)
						(arc
							(start -0.3048 0.2032)
							(mid -0.275042 0.275042)
							(end -0.2032 0.3048)
						)
						(arc
							(start 0.2032 0.3048)
							(mid 0.275042 0.275042)
							(end 0.3048 0.2032)
						)
					)
					(width 0)
					(fill yes)
				)
			)
		)
		(pad "2" smd custom
			(at 0 0.4445 270)
			(size 0.1524 0.1524)
			(layers "F.Cu" "F.Mask" "F.Paste")
			(net "GND")
			(options
				(clearance outline)
				(anchor circle)
			)
			(primitives
				(gr_poly
					(pts
						(arc
							(start 0.3048 -0.2032)
							(mid 0.275042 -0.275042)
							(end 0.2032 -0.3048)
						)
						(arc
							(start -0.2032 -0.3048)
							(mid -0.275042 -0.275042)
							(end -0.3048 -0.2032)
						)
						(arc
							(start -0.3048 0.2032)
							(mid -0.275042 0.275042)
							(end -0.2032 0.3048)
						)
						(arc
							(start 0.2032 0.3048)
							(mid 0.275042 0.275042)
							(end 0.3048 0.2032)
						)
					)
					(width 0)
					(fill yes)
				)
			)
		)
	)
	(footprint ""
		(layer "F.Cu")
		(at 175.697134 -56.7182)
		(property "Reference" "TP136"
			(at 0 0 0)
			(layer "F.SilkS")
			(hide yes)
			(effects
				(font
					(size 1.27 1.27)
				)
			)
		)
		(property "Value" "TPAD28-2-GP"
			(at -0.0127 -1.6637 0)
			(unlocked yes)
			(layer "F.Fab")
			(hide yes)
			(effects
				(font
					(size 1.016 1.016)
					(thickness 0.1524)
				)
			)
		)
		(property "Device Type" "TPAD28"
			(at -0.0127 -3.1877 0)
			(unlocked yes)
			(layer "F.Fab")
			(hide yes)
			(effects
				(font
					(size 1.016 1.016)
					(thickness 0.1524)
				)
			)
		)
		(duplicate_pad_numbers_are_jumpers no)
		(fp_poly
			(pts
				(arc
					(start 0.3556 0)
					(mid -0.3556 0)
					(end 0.3556 0)
				)
			)
			(stroke
				(width 0)
				(type default)
			)
			(fill no)
			(layer "F.CrtYd")
		)
		(fp_poly
			(pts
				(arc
					(start 0.6096 0)
					(mid -0.6096 0)
					(end 0.6096 0)
				)
			)
			(stroke
				(width 0)
				(type default)
			)
			(fill no)
			(layer "F.Fab")
		)
		(pad "1" smd circle
			(at 0 0)
			(size 0.7112 0.7112)
			(layers "F.Cu" "F.Mask" "F.Paste")
			(net "JTAG_IOC_TDI")
		)
	)
	(footprint ""
		(layer "F.Cu")
		(at 149.837648 -38.566598 102)
		(property "Reference" "C331"
			(at 0 0 102)
			(layer "F.SilkS")
			(hide yes)
			(effects
				(font
					(size 1.27 1.27)
				)
			)
		)
		(property "Value" "SCD01U16V1KX-GP"
			(at -2.832048 -1.739777 102)
			(unlocked yes)
			(layer "F.Fab")
			(hide yes)
			(effects
				(font
					(size 1.016 1.016)
					(thickness 0.1524)
				)
			)
		)
		(property "Device Type" "C0201H13"
			(at -2.831925 -3.263781 102)
			(unlocked yes)
			(layer "F.Fab")
			(hide yes)
			(effects
				(font
					(size 1.016 1.016)
					(thickness 0.1524)
				)
			)
		)
		(duplicate_pad_numbers_are_jumpers no)
		(fp_poly
			(pts
				(xy -0.279454 -0.647706) (xy 0.279346 -0.647706) (xy 0.279346 0.647694) (xy -0.279454 0.647694)
			)
			(stroke
				(width 0)
				(type default)
			)
			(fill no)
			(layer "F.CrtYd")
		)
		(fp_poly
			(pts
				(xy -0.279454 -0.647706) (xy 0.279346 -0.647706) (xy 0.279346 0.647694) (xy -0.279454 0.647694)
			)
			(stroke
				(width 0)
				(type default)
			)
			(fill no)
			(layer "F.Fab")
		)
		(pad "1" smd custom
			(at -0.000001 -0.2794 102)
			(size 0.0762 0.0762)
			(layers "F.Cu" "F.Mask" "F.Paste")
			(net "PHY_SCC_TO_IOC_42_DP")
			(options
				(clearance outline)
				(anchor circle)
			)
			(primitives
				(gr_poly
					(pts
						(arc
							(start 0.1524 -0.127)
							(mid 0.137521 -0.162921)
							(end 0.1016 -0.1778)
						)
						(arc
							(start -0.1016 -0.1778)
							(mid -0.137521 -0.162921)
							(end -0.1524 -0.127)
						)
						(arc
							(start -0.1524 0.127)
							(mid -0.137521 0.162921)
							(end -0.1016 0.1778)
						)
						(arc
							(start 0.1016 0.1778)
							(mid 0.137521 0.162921)
							(end 0.1524 0.127)
						)
					)
					(width 0)
					(fill yes)
				)
			)
		)
		(pad "2" smd custom
			(at 0.000001 0.2794 102)
			(size 0.0762 0.0762)
			(layers "F.Cu" "F.Mask" "F.Paste")
			(net "PHY_SCC_TO_IOC_C_42_DP")
			(options
				(clearance outline)
				(anchor circle)
			)
			(primitives
				(gr_poly
					(pts
						(arc
							(start 0.1524 -0.127)
							(mid 0.137521 -0.162921)
							(end 0.1016 -0.1778)
						)
						(arc
							(start -0.1016 -0.1778)
							(mid -0.137521 -0.162921)
							(end -0.1524 -0.127)
						)
						(arc
							(start -0.1524 0.127)
							(mid -0.137521 0.162921)
							(end -0.1016 0.1778)
						)
						(arc
							(start 0.1016 0.1778)
							(mid 0.137521 0.162921)
							(end 0.1524 0.127)
						)
					)
					(width 0)
					(fill yes)
				)
			)
		)
	)
)
